(kicad_pcb
	(version 20260206)
	(generator "pcbnew")
	(generator_version "10.0")
	(general
		(thickness 1.6)
		(legacy_teardrops no)
	)
	(paper "A4")
	(title_block
		(title "fcb — 12433-1M.1206WZS1330.brd")
		(comment 1 "Open Vault / Knox (Wiwynn) / footprints 178-183 of 495")
	)
	(layers
		(0 "F.Cu" signal "TOP")
		(4 "In1.Cu" signal "L2GND")
		(6 "In2.Cu" signal "L3VCC")
		(2 "B.Cu" signal "BOTTOM")
		(9 "F.Adhes" user "F.Adhesive")
		(11 "B.Adhes" user "B.Adhesive")
		(13 "F.Paste" user "Package Geometry/Pastemask Top")
		(15 "B.Paste" user "Package Geometry/Pastemask Bottom")
		(5 "F.SilkS" user "Ref Des/Silkscreen Top")
		(7 "B.SilkS" user "Ref Des/Silkscreen Bottom")
		(1 "F.Mask" user "Board Geometry/Soldermask Top")
		(3 "B.Mask" user "Board Geometry/Soldermask Bottom")
		(17 "Dwgs.User" user "User.Drawings")
		(19 "Cmts.User" user "User.Comments")
		(21 "Eco1.User" user "User.Eco1")
		(23 "Eco2.User" user "User.Eco2")
		(25 "Edge.Cuts" user "Board Geometry/Outline")
		(27 "Margin" user)
		(31 "F.CrtYd" user "Package Geometry/Place Bound Top")
		(29 "B.CrtYd" user "Package Geometry/Place Bound Bottom")
		(35 "F.Fab" user "Ref Des/Assembly Top")
		(33 "B.Fab" user "Ref Des/Assembly Bottom")
	)
	(footprint ""
		(layer "F.Cu")
		(at 20.585938 -15.595092 -90)
		(property "Reference" "R73"
			(at 0 0 270)
			(layer "F.SilkS")
			(hide yes)
			(effects
				(font
					(size 1.27 1.27)
				)
			)
		)
		(property "Value" "27KR3F-GP"
			(at -0.0254 -2.5146 270)
			(unlocked yes)
			(layer "F.Fab")
			(hide yes)
			(effects
				(font
					(size 1.016 1.016)
					(thickness 0.1524)
				)
			)
		)
		(property "Device Type" "R603H22"
			(at -0.0254 -4.0386 270)
			(unlocked yes)
			(layer "F.Fab")
			(hide yes)
			(effects
				(font
					(size 1.016 1.016)
					(thickness 0.1524)
				)
			)
		)
		(duplicate_pad_numbers_are_jumpers no)
		(fp_line
			(start -0.4826 0)
			(end -0.2032 0)
			(stroke
				(width 0.2032)
				(type default)
			)
			(layer "F.SilkS")
		)
		(fp_line
			(start 0.2032 0)
			(end 0.4826 0)
			(stroke
				(width 0.2032)
				(type default)
			)
			(layer "F.SilkS")
		)
		(fp_rect
			(start -0.5842 1.3335)
			(end 0.5842 -1.3335)
			(stroke
				(width 0)
				(type default)
			)
			(fill no)
			(layer "F.CrtYd")
		)
		(fp_rect
			(start -0.5842 1.3335)
			(end 0.5842 -1.3335)
			(stroke
				(width 0)
				(type default)
			)
			(fill no)
			(layer "F.Fab")
		)
		(pad "1" smd custom
			(at 0 -0.762 270)
			(size 0.2159 0.2159)
			(layers "F.Cu" "F.Mask" "F.Paste")
			(net "FANIN_11")
			(options
				(clearance outline)
				(anchor circle)
			)
			(primitives
				(gr_poly
					(pts
						(arc
							(start -0.3302 -0.4318)
							(mid -0.402042 -0.402042)
							(end -0.4318 -0.3302)
						)
						(arc
							(start -0.4318 0.3302)
							(mid -0.402042 0.402042)
							(end -0.3302 0.4318)
						)
						(arc
							(start 0.3302 0.4318)
							(mid 0.402042 0.402042)
							(end 0.4318 0.3302)
						)
						(arc
							(start 0.4318 -0.3302)
							(mid 0.402042 -0.402042)
							(end 0.3302 -0.4318)
						)
					)
					(width 0)
					(fill yes)
				)
			)
		)
		(pad "2" smd custom
			(at 0 0.762 270)
			(size 0.2159 0.2159)
			(layers "F.Cu" "F.Mask" "F.Paste")
			(net "FAN_TACH11")
			(options
				(clearance outline)
				(anchor circle)
			)
			(primitives
				(gr_poly
					(pts
						(arc
							(start -0.3302 -0.4318)
							(mid -0.402042 -0.402042)
							(end -0.4318 -0.3302)
						)
						(arc
							(start -0.4318 0.3302)
							(mid -0.402042 0.402042)
							(end -0.3302 0.4318)
						)
						(arc
							(start 0.3302 0.4318)
							(mid 0.402042 0.402042)
							(end 0.4318 0.3302)
						)
						(arc
							(start 0.4318 -0.3302)
							(mid 0.402042 -0.402042)
							(end 0.3302 -0.4318)
						)
					)
					(width 0)
					(fill yes)
				)
			)
		)
	)
	(footprint ""
		(layer "F.Cu")
		(at 8.3058 -64.8208)
		(property "Reference" "R25"
			(at 0 0 0)
			(layer "F.SilkS")
			(hide yes)
			(effects
				(font
					(size 1.27 1.27)
				)
			)
		)
		(property "Value" "33R2F-3-GP"
			(at 0.064008 -3.993896 0)
			(unlocked yes)
			(layer "F.Fab")
			(hide yes)
			(effects
				(font
					(size 1.016 1.016)
					(thickness 0.1524)
				)
			)
		)
		(property "Device Type" "R402H16"
			(at 0.064008 -5.517896 0)
			(unlocked yes)
			(layer "F.Fab")
			(hide yes)
			(effects
				(font
					(size 1.016 1.016)
					(thickness 0.1524)
				)
			)
		)
		(duplicate_pad_numbers_are_jumpers no)
		(fp_line
			(start -0.508 -0.9398)
			(end -0.508 0.9398)
			(stroke
				(width 0.1524)
				(type default)
			)
			(layer "F.SilkS")
		)
		(fp_line
			(start 0.508 -0.9398)
			(end -0.508 -0.9398)
			(stroke
				(width 0.1524)
				(type default)
			)
			(layer "F.SilkS")
		)
		(fp_rect
			(start -0.508 0.9398)
			(end 0.508 -0.9398)
			(stroke
				(width 0)
				(type default)
			)
			(fill no)
			(layer "F.CrtYd")
		)
		(fp_rect
			(start -0.508 0.9398)
			(end 0.508 -0.9398)
			(stroke
				(width 0)
				(type default)
			)
			(fill no)
			(layer "F.Fab")
		)
		(pad "1" smd custom
			(at 0 -0.4445)
			(size 0.1397 0.1397)
			(layers "F.Cu" "F.Mask" "F.Paste")
			(net "P3V3")
			(options
				(clearance outline)
				(anchor circle)
			)
			(primitives
				(gr_poly
					(pts
						(arc
							(start -0.1778 -0.2794)
							(mid -0.249642 -0.249642)
							(end -0.2794 -0.1778)
						)
						(arc
							(start -0.2794 0.1778)
							(mid -0.249642 0.249642)
							(end -0.1778 0.2794)
						)
						(arc
							(start 0.1778 0.2794)
							(mid 0.249642 0.249642)
							(end 0.2794 0.1778)
						)
						(arc
							(start 0.2794 -0.1778)
							(mid 0.249642 -0.249642)
							(end 0.1778 -0.2794)
						)
					)
					(width 0)
					(fill yes)
				)
			)
		)
		(pad "2" smd custom
			(at 0 0.4445)
			(size 0.1397 0.1397)
			(layers "F.Cu" "F.Mask" "F.Paste")
			(net "LED_DR_LED5_BLUE")
			(options
				(clearance outline)
				(anchor circle)
			)
			(primitives
				(gr_poly
					(pts
						(arc
							(start -0.1778 -0.2794)
							(mid -0.249642 -0.249642)
							(end -0.2794 -0.1778)
						)
						(arc
							(start -0.2794 0.1778)
							(mid -0.249642 0.249642)
							(end -0.1778 0.2794)
						)
						(arc
							(start 0.1778 0.2794)
							(mid 0.249642 0.249642)
							(end 0.2794 0.1778)
						)
						(arc
							(start 0.2794 -0.1778)
							(mid 0.249642 -0.249642)
							(end 0.1778 -0.2794)
						)
					)
					(width 0)
					(fill yes)
				)
			)
		)
	)
	(footprint ""
		(layer "F.Cu")
		(at 8.733028 -67.111118 -90)
		(property "Reference" "R111"
			(at 0 0 270)
			(layer "F.SilkS")
			(hide yes)
			(effects
				(font
					(size 1.27 1.27)
				)
			)
		)
		(property "Value" "2KR2F-3-GP"
			(at 0.064008 -3.993896 270)
			(unlocked yes)
			(layer "F.Fab")
			(hide yes)
			(effects
				(font
					(size 1.016 1.016)
					(thickness 0.1524)
				)
			)
		)
		(property "Device Type" "R402H16"
			(at 0.064008 -5.517896 270)
			(unlocked yes)
			(layer "F.Fab")
			(hide yes)
			(effects
				(font
					(size 1.016 1.016)
					(thickness 0.1524)
				)
			)
		)
		(duplicate_pad_numbers_are_jumpers no)
		(fp_line
			(start -0.508 -0.9398)
			(end -0.508 0.9398)
			(stroke
				(width 0.1524)
				(type default)
			)
			(layer "F.SilkS")
		)
		(fp_line
			(start 0.508 -0.9398)
			(end -0.508 -0.9398)
			(stroke
				(width 0.1524)
				(type default)
			)
			(layer "F.SilkS")
		)
		(fp_rect
			(start -0.508 0.9398)
			(end 0.508 -0.9398)
			(stroke
				(width 0)
				(type default)
			)
			(fill no)
			(layer "F.CrtYd")
		)
		(fp_rect
			(start -0.508 0.9398)
			(end 0.508 -0.9398)
			(stroke
				(width 0)
				(type default)
			)
			(fill no)
			(layer "F.Fab")
		)
		(pad "1" smd custom
			(at 0 -0.4445 270)
			(size 0.1397 0.1397)
			(layers "F.Cu" "F.Mask" "F.Paste")
			(net "LED_DR_LED5")
			(options
				(clearance outline)
				(anchor circle)
			)
			(primitives
				(gr_poly
					(pts
						(arc
							(start -0.1778 -0.2794)
							(mid -0.249642 -0.249642)
							(end -0.2794 -0.1778)
						)
						(arc
							(start -0.2794 0.1778)
							(mid -0.249642 0.249642)
							(end -0.1778 0.2794)
						)
						(arc
							(start 0.1778 0.2794)
							(mid 0.249642 0.249642)
							(end 0.2794 0.1778)
						)
						(arc
							(start 0.2794 -0.1778)
							(mid 0.249642 -0.249642)
							(end 0.1778 -0.2794)
						)
					)
					(width 0)
					(fill yes)
				)
			)
		)
		(pad "2" smd custom
			(at 0 0.4445 270)
			(size 0.1397 0.1397)
			(layers "F.Cu" "F.Mask" "F.Paste")
			(net "LED_DR_LED5_B")
			(options
				(clearance outline)
				(anchor circle)
			)
			(primitives
				(gr_poly
					(pts
						(arc
							(start -0.1778 -0.2794)
							(mid -0.249642 -0.249642)
							(end -0.2794 -0.1778)
						)
						(arc
							(start -0.2794 0.1778)
							(mid -0.249642 0.249642)
							(end -0.1778 0.2794)
						)
						(arc
							(start 0.1778 0.2794)
							(mid 0.249642 0.249642)
							(end 0.2794 0.1778)
						)
						(arc
							(start 0.2794 -0.1778)
							(mid 0.249642 -0.249642)
							(end 0.1778 -0.2794)
						)
					)
					(width 0)
					(fill yes)
				)
			)
		)
	)
	(footprint ""
		(layer "F.Cu")
		(at 21.209 -371.729)
		(property "Reference" "PR33"
			(at 0 0 0)
			(layer "F.SilkS")
			(hide yes)
			(effects
				(font
					(size 1.27 1.27)
				)
			)
		)
		(property "Value" "51KR2F-L-GP"
			(at 0.064008 -3.993896 0)
			(unlocked yes)
			(layer "F.Fab")
			(hide yes)
			(effects
				(font
					(size 1.016 1.016)
					(thickness 0.1524)
				)
			)
		)
		(property "Device Type" "R402H16"
			(at 0.064008 -5.517896 0)
			(unlocked yes)
			(layer "F.Fab")
			(hide yes)
			(effects
				(font
					(size 1.016 1.016)
					(thickness 0.1524)
				)
			)
		)
		(duplicate_pad_numbers_are_jumpers no)
		(fp_line
			(start -0.508 -0.9398)
			(end -0.508 0.9398)
			(stroke
				(width 0.1524)
				(type default)
			)
			(layer "F.SilkS")
		)
		(fp_line
			(start 0.508 -0.9398)
			(end -0.508 -0.9398)
			(stroke
				(width 0.1524)
				(type default)
			)
			(layer "F.SilkS")
		)
		(fp_rect
			(start -0.508 0.9398)
			(end 0.508 -0.9398)
			(stroke
				(width 0)
				(type default)
			)
			(fill no)
			(layer "F.CrtYd")
		)
		(fp_rect
			(start -0.508 0.9398)
			(end 0.508 -0.9398)
			(stroke
				(width 0)
				(type default)
			)
			(fill no)
			(layer "F.Fab")
		)
		(pad "1" smd custom
			(at 0 -0.4445)
			(size 0.1397 0.1397)
			(layers "F.Cu" "F.Mask" "F.Paste")
			(net "P12V_AUX")
			(options
				(clearance outline)
				(anchor circle)
			)
			(primitives
				(gr_poly
					(pts
						(arc
							(start -0.1778 -0.2794)
							(mid -0.249642 -0.249642)
							(end -0.2794 -0.1778)
						)
						(arc
							(start -0.2794 0.1778)
							(mid -0.249642 0.249642)
							(end -0.1778 0.2794)
						)
						(arc
							(start 0.1778 0.2794)
							(mid 0.249642 0.249642)
							(end 0.2794 0.1778)
						)
						(arc
							(start 0.2794 -0.1778)
							(mid 0.249642 -0.249642)
							(end 0.1778 -0.2794)
						)
					)
					(width 0)
					(fill yes)
				)
			)
		)
		(pad "2" smd custom
			(at 0 0.4445)
			(size 0.1397 0.1397)
			(layers "F.Cu" "F.Mask" "F.Paste")
			(net "ADM1276_OV")
			(options
				(clearance outline)
				(anchor circle)
			)
			(primitives
				(gr_poly
					(pts
						(arc
							(start -0.1778 -0.2794)
							(mid -0.249642 -0.249642)
							(end -0.2794 -0.1778)
						)
						(arc
							(start -0.2794 0.1778)
							(mid -0.249642 0.249642)
							(end -0.1778 0.2794)
						)
						(arc
							(start 0.1778 0.2794)
							(mid 0.249642 0.249642)
							(end 0.2794 0.1778)
						)
						(arc
							(start 0.2794 -0.1778)
							(mid 0.249642 -0.249642)
							(end 0.1778 -0.2794)
						)
					)
					(width 0)
					(fill yes)
				)
			)
		)
	)
	(footprint ""
		(layer "F.Cu")
		(at 47.0154 -418.592 90)
		(property "Reference" "C25"
			(at 0 0 90)
			(layer "F.SilkS")
			(hide yes)
			(effects
				(font
					(size 1.27 1.27)
				)
			)
		)
		(property "Value" "SCD1U50V3KX-GP"
			(at 0 -2.8194 90)
			(unlocked yes)
			(layer "F.Fab")
			(hide yes)
			(effects
				(font
					(size 1.016 1.016)
					(thickness 0.1524)
				)
			)
		)
		(property "Device Type" "C603H36"
			(at 0 -4.3434 90)
			(unlocked yes)
			(layer "F.Fab")
			(hide yes)
			(effects
				(font
					(size 1.016 1.016)
					(thickness 0.1524)
				)
			)
		)
		(duplicate_pad_numbers_are_jumpers no)
		(fp_line
			(start 0.508 0)
			(end -0.508 0)
			(stroke
				(width 0.2032)
				(type default)
			)
			(layer "F.SilkS")
		)
		(fp_rect
			(start -0.5842 1.3335)
			(end 0.5842 -1.3335)
			(stroke
				(width 0)
				(type default)
			)
			(fill no)
			(layer "F.CrtYd")
		)
		(fp_rect
			(start -0.5842 1.3335)
			(end 0.5842 -1.3335)
			(stroke
				(width 0)
				(type default)
			)
			(fill no)
			(layer "F.Fab")
		)
		(pad "1" smd custom
			(at 0 -0.762 90)
			(size 0.2159 0.2159)
			(layers "F.Cu" "F.Mask" "F.Paste")
			(net "P12V_AUX")
			(options
				(clearance outline)
				(anchor circle)
			)
			(primitives
				(gr_poly
					(pts
						(arc
							(start -0.3302 -0.4318)
							(mid -0.402042 -0.402042)
							(end -0.4318 -0.3302)
						)
						(arc
							(start -0.4318 0.3302)
							(mid -0.402042 0.402042)
							(end -0.3302 0.4318)
						)
						(arc
							(start 0.3302 0.4318)
							(mid 0.402042 0.402042)
							(end 0.4318 0.3302)
						)
						(arc
							(start 0.4318 -0.3302)
							(mid 0.402042 -0.402042)
							(end 0.3302 -0.4318)
						)
					)
					(width 0)
					(fill yes)
				)
			)
		)
		(pad "2" smd custom
			(at 0 0.762 90)
			(size 0.2159 0.2159)
			(layers "F.Cu" "F.Mask" "F.Paste")
			(net "GND")
			(options
				(clearance outline)
				(anchor circle)
			)
			(primitives
				(gr_poly
					(pts
						(arc
							(start -0.3302 -0.4318)
							(mid -0.402042 -0.402042)
							(end -0.4318 -0.3302)
						)
						(arc
							(start -0.4318 0.3302)
							(mid -0.402042 0.402042)
							(end -0.3302 0.4318)
						)
						(arc
							(start 0.3302 0.4318)
							(mid 0.402042 0.402042)
							(end 0.4318 0.3302)
						)
						(arc
							(start 0.4318 -0.3302)
							(mid 0.402042 -0.402042)
							(end 0.3302 -0.4318)
						)
					)
					(width 0)
					(fill yes)
				)
			)
		)
	)
	(footprint ""
		(layer "F.Cu")
		(at 20.381976 -176.43729 -90)
		(property "Reference" "R24"
			(at 0 0 270)
			(layer "F.SilkS")
			(hide yes)
			(effects
				(font
					(size 1.27 1.27)
				)
			)
		)
		(property "Value" "4K7R2F-GP"
			(at 0.064008 -3.993896 270)
			(unlocked yes)
			(layer "F.Fab")
			(hide yes)
			(effects
				(font
					(size 1.016 1.016)
					(thickness 0.1524)
				)
			)
		)
		(property "Device Type" "R402H16"
			(at 0.064008 -5.517896 270)
			(unlocked yes)
			(layer "F.Fab")
			(hide yes)
			(effects
				(font
					(size 1.016 1.016)
					(thickness 0.1524)
				)
			)
		)
		(duplicate_pad_numbers_are_jumpers no)
		(fp_line
			(start -0.508 -0.9398)
			(end -0.508 0.9398)
			(stroke
				(width 0.1524)
				(type default)
			)
			(layer "F.SilkS")
		)
		(fp_line
			(start 0.508 -0.9398)
			(end -0.508 -0.9398)
			(stroke
				(width 0.1524)
				(type default)
			)
			(layer "F.SilkS")
		)
		(fp_rect
			(start -0.508 0.9398)
			(end 0.508 -0.9398)
			(stroke
				(width 0)
				(type default)
			)
			(fill no)
			(layer "F.CrtYd")
		)
		(fp_rect
			(start -0.508 0.9398)
			(end 0.508 -0.9398)
			(stroke
				(width 0)
				(type default)
			)
			(fill no)
			(layer "F.Fab")
		)
		(pad "1" smd custom
			(at 0 -0.4445 270)
			(size 0.1397 0.1397)
			(layers "F.Cu" "F.Mask" "F.Paste")
			(net "NCT7368S_SEL")
			(options
				(clearance outline)
				(anchor circle)
			)
			(primitives
				(gr_poly
					(pts
						(arc
							(start -0.1778 -0.2794)
							(mid -0.249642 -0.249642)
							(end -0.2794 -0.1778)
						)
						(arc
							(start -0.2794 0.1778)
							(mid -0.249642 0.249642)
							(end -0.1778 0.2794)
						)
						(arc
							(start 0.1778 0.2794)
							(mid 0.249642 0.249642)
							(end 0.2794 0.1778)
						)
						(arc
							(start 0.2794 -0.1778)
							(mid 0.249642 -0.249642)
							(end 0.1778 -0.2794)
						)
					)
					(width 0)
					(fill yes)
				)
			)
		)
		(pad "2" smd custom
			(at 0 0.4445 270)
			(size 0.1397 0.1397)
			(layers "F.Cu" "F.Mask" "F.Paste")
			(net "GND")
			(options
				(clearance outline)
				(anchor circle)
			)
			(primitives
				(gr_poly
					(pts
						(arc
							(start -0.1778 -0.2794)
							(mid -0.249642 -0.249642)
							(end -0.2794 -0.1778)
						)
						(arc
							(start -0.2794 0.1778)
							(mid -0.249642 0.249642)
							(end -0.1778 0.2794)
						)
						(arc
							(start 0.1778 0.2794)
							(mid 0.249642 0.249642)
							(end 0.2794 0.1778)
						)
						(arc
							(start 0.2794 -0.1778)
							(mid 0.249642 -0.249642)
							(end 0.1778 -0.2794)
						)
					)
					(width 0)
					(fill yes)
				)
			)
		)
	)
)
